(kicad_pcb
	(version 20260206)
	(generator "pcbnew")
	(generator_version "10.0")
	(general
		(thickness 1.6)
		(legacy_teardrops no)
	)
	(paper "A4")
	(title_block
		(title "netronome-mezz — pcbd0082-001_rev01_jul9_a.brd")
		(comment 1 "Open CloudServer (Microsoft) / footprints 571-582 of 714")
	)
	(layers
		(0 "F.Cu" signal "TOP")
		(4 "In1.Cu" signal "02_GND")
		(6 "In2.Cu" signal "03_SIG")
		(8 "In3.Cu" signal "04_SIG")
		(10 "In4.Cu" signal "05_GND")
		(12 "In5.Cu" signal "06_PWR1")
		(14 "In6.Cu" signal "07_SIG")
		(16 "In7.Cu" signal "08_SIG")
		(18 "In8.Cu" signal "09_GND")
		(2 "B.Cu" signal "BOTTOM")
		(9 "F.Adhes" user "F.Adhesive")
		(11 "B.Adhes" user "B.Adhesive")
		(13 "F.Paste" user "Package Geometry/Pastemask Top")
		(15 "B.Paste" user "Package Geometry/Pastemask Bottom")
		(5 "F.SilkS" user "Ref Des/Silkscreen Top")
		(7 "B.SilkS" user "Ref Des/Silkscreen Bottom")
		(1 "F.Mask" user "Board Geometry/Soldermask Top")
		(3 "B.Mask" user "Board Geometry/Soldermask Bottom")
		(17 "Dwgs.User" user "User.Drawings")
		(19 "Cmts.User" user "User.Comments")
		(21 "Eco1.User" user "User.Eco1")
		(23 "Eco2.User" user "User.Eco2")
		(25 "Edge.Cuts" user "Board Geometry/Outline")
		(27 "Margin" user)
		(31 "F.CrtYd" user "Package Geometry/Place Bound Top")
		(29 "B.CrtYd" user "Package Geometry/Place Bound Bottom")
		(35 "F.Fab" user "Ref Des/Assembly Top")
		(33 "B.Fab" user "Ref Des/Assembly Bottom")
		(45 "User.4" user "COMPVAL_TYPE_BOTTOM")
	)
	(footprint ""
		(layer "B.Cu")
		(at 57.236995 13.54201)
		(property "Reference" "C161"
			(at -0.494665 2.96799 270)
			(unlocked yes)
			(layer "B.SilkS")
			(effects
				(font
					(size 0.7874 0.5842)
					(thickness 0.127)
				)
				(justify mirror)
			)
		)
		(property "Value" ""
			(at 0 0 0)
			(layer "B.Fab")
			(effects
				(font
					(size 1.27 1.27)
				)
				(justify mirror)
			)
		)
		(duplicate_pad_numbers_are_jumpers no)
		(fp_circle
			(center 0 0)
			(end 0.104648 0)
			(stroke
				(width 0.1016)
				(type default)
			)
			(fill no)
			(layer "B.SilkS")
		)
		(fp_poly
			(pts
				(xy 0.381 -0.889) (xy 0.381 0.889) (xy -0.381 0.889) (xy -0.381 -0.889)
			)
			(stroke
				(width 0)
				(type default)
			)
			(fill no)
			(layer "B.CrtYd")
		)
		(fp_line
			(start -0.508 -1.016)
			(end -0.508 1.016)
			(stroke
				(width 0.0254)
				(type default)
			)
			(layer "B.Fab")
		)
		(fp_line
			(start -0.508 1.016)
			(end 0.508 1.016)
			(stroke
				(width 0.0254)
				(type default)
			)
			(layer "B.Fab")
		)
		(fp_line
			(start 0.254 -1.016)
			(end -0.508 -1.016)
			(stroke
				(width 0.0254)
				(type default)
			)
			(layer "B.Fab")
		)
		(fp_line
			(start 0.508 -1.016)
			(end 0.254 -1.016)
			(stroke
				(width 0.0254)
				(type default)
			)
			(layer "B.Fab")
		)
		(fp_line
			(start 0.508 1.016)
			(end 0.508 -1.016)
			(stroke
				(width 0.0254)
				(type default)
			)
			(layer "B.Fab")
		)
		(pad "1" smd custom
			(at 0 -0.500126 180)
			(size 0.127 0.127)
			(layers "B.Cu" "B.Mask" "B.Paste")
			(net "VDD_CORE")
			(options
				(clearance outline)
				(anchor circle)
			)
			(primitives
				(gr_poly
					(pts
						(xy -0.1778 0.254) (xy 0.1778 0.254) (xy 0.254 0.1778) (xy 0.254 -0.1778) (xy 0.1778 -0.254) (xy -0.1778 -0.254)
						(xy -0.254 -0.1778) (xy -0.254 0.1778)
					)
					(width 0)
					(fill yes)
				)
			)
		)
		(pad "2" smd custom
			(at 0 0.500126 180)
			(size 0.127 0.127)
			(layers "B.Cu" "B.Mask" "B.Paste")
			(net "GND")
			(options
				(clearance outline)
				(anchor circle)
			)
			(primitives
				(gr_poly
					(pts
						(xy -0.1778 0.254) (xy 0.1778 0.254) (xy 0.254 0.1778) (xy 0.254 -0.1778) (xy 0.1778 -0.254) (xy -0.1778 -0.254)
						(xy -0.254 -0.1778) (xy -0.254 0.1778)
					)
					(width 0)
					(fill yes)
				)
			)
		)
	)
	(footprint ""
		(layer "B.Cu")
		(at 35.179 46.736)
		(property "Reference" "TP7"
			(at 0 0 0)
			(layer "B.SilkS")
			(hide yes)
			(effects
				(font
					(size 1.27 1.27)
				)
				(justify mirror)
			)
		)
		(property "Value" "*"
			(at 0.4826 -0.14732 0)
			(unlocked yes)
			(layer "B.Fab")
			(hide yes)
			(effects
				(font
					(size 1.27 0.9652)
					(thickness 0.000001)
				)
				(justify left mirror)
			)
		)
		(property "Device Type" "TP_SMALL"
			(at 0.4826 -0.14732 0)
			(unlocked yes)
			(layer "B.Fab")
			(hide yes)
			(effects
				(font
					(size 1.27 0.9652)
					(thickness 0.000001)
				)
				(justify left mirror)
			)
		)
		(duplicate_pad_numbers_are_jumpers no)
		(fp_line
			(start -0.8636 -0.8636)
			(end 0.8636 -0.8636)
			(stroke
				(width 0.1524)
				(type default)
			)
			(layer "B.SilkS")
		)
		(fp_line
			(start -0.8636 0.8636)
			(end -0.8636 -0.8636)
			(stroke
				(width 0.1524)
				(type default)
			)
			(layer "B.SilkS")
		)
		(fp_line
			(start 0.8636 -0.8636)
			(end 0.8636 0.8636)
			(stroke
				(width 0.1524)
				(type default)
			)
			(layer "B.SilkS")
		)
		(fp_line
			(start 0.8636 0.8636)
			(end -0.8636 0.8636)
			(stroke
				(width 0.1524)
				(type default)
			)
			(layer "B.SilkS")
		)
		(fp_poly
			(pts
				(xy 0.635 -0.635) (xy 0.635 0.635) (xy -0.635 0.635) (xy -0.635 -0.635)
			)
			(stroke
				(width 0)
				(type default)
			)
			(fill no)
			(layer "B.CrtYd")
		)
		(pad "1" smd rect
			(at 0 0 180)
			(size 1.27 1.27)
			(layers "B.Cu" "B.Mask" "B.Paste")
			(net "NFP_JTAG_ARM_TDI")
		)
	)
	(footprint ""
		(layer "B.Cu")
		(at 76.251003 13.456006)
		(property "Reference" "V_A-DQ17"
			(at 0 0 0)
			(layer "B.SilkS")
			(hide yes)
			(effects
				(font
					(size 1.27 1.27)
				)
				(justify mirror)
			)
		)
		(property "Value" ""
			(at 0 0 0)
			(layer "B.Fab")
			(effects
				(font
					(size 1.27 1.27)
				)
				(justify mirror)
			)
		)
		(duplicate_pad_numbers_are_jumpers no)
		(pad "1" thru_hole circle
			(at 0 0 180)
			(size 0.4572 0.4572)
			(drill 0.20574)
			(layers "*.Cu" "*.Mask")
			(remove_unused_layers no)
			(net "DDR0_32A_DQ17")
			(clearance 0.1143)
			(thermal_gap 0.1143)
		)
	)
	(footprint ""
		(layer "B.Cu")
		(at 43.18 46.101)
		(property "Reference" "TP19"
			(at 2.159 -1.49733 0)
			(unlocked yes)
			(layer "B.SilkS")
			(effects
				(font
					(size 0.7874 0.5842)
					(thickness 0.127)
				)
				(justify left mirror)
			)
		)
		(property "Value" "*"
			(at 0.4826 -0.14732 0)
			(unlocked yes)
			(layer "B.Fab")
			(hide yes)
			(effects
				(font
					(size 1.27 0.9652)
					(thickness 0.000001)
				)
				(justify left mirror)
			)
		)
		(property "Device Type" "TP_SMALL"
			(at 0.4826 -0.14732 0)
			(unlocked yes)
			(layer "B.Fab")
			(hide yes)
			(effects
				(font
					(size 1.27 0.9652)
					(thickness 0.000001)
				)
				(justify left mirror)
			)
		)
		(duplicate_pad_numbers_are_jumpers no)
		(fp_line
			(start -0.8636 -0.8636)
			(end 0.8636 -0.8636)
			(stroke
				(width 0.1524)
				(type default)
			)
			(layer "B.SilkS")
		)
		(fp_line
			(start -0.8636 0.8636)
			(end -0.8636 -0.8636)
			(stroke
				(width 0.1524)
				(type default)
			)
			(layer "B.SilkS")
		)
		(fp_line
			(start 0.8636 -0.8636)
			(end 0.8636 0.8636)
			(stroke
				(width 0.1524)
				(type default)
			)
			(layer "B.SilkS")
		)
		(fp_line
			(start 0.8636 0.8636)
			(end -0.8636 0.8636)
			(stroke
				(width 0.1524)
				(type default)
			)
			(layer "B.SilkS")
		)
		(fp_poly
			(pts
				(xy 0.635 -0.635) (xy 0.635 0.635) (xy -0.635 0.635) (xy -0.635 -0.635)
			)
			(stroke
				(width 0)
				(type default)
			)
			(fill no)
			(layer "B.CrtYd")
		)
		(pad "1" smd rect
			(at 0 0 180)
			(size 1.27 1.27)
			(layers "B.Cu" "B.Mask" "B.Paste")
			(net "NFP_UART_SR_TX")
		)
	)
	(footprint ""
		(layer "B.Cu")
		(at 54.737 24.9428 180)
		(property "Reference" "C7"
			(at -0.762 1.87833 0)
			(unlocked yes)
			(layer "B.SilkS")
			(effects
				(font
					(size 0.7874 0.5842)
					(thickness 0.127)
				)
				(justify left mirror)
			)
		)
		(property "Value" "22UF"
			(at 0.148158 1.7526 90)
			(unlocked yes)
			(layer "B.Fab")
			(hide yes)
			(effects
				(font
					(size 1.27 0.9652)
					(thickness 0.000001)
				)
				(justify left mirror)
			)
		)
		(property "Device Type" "CAPC0063"
			(at 0.148158 1.7526 90)
			(unlocked yes)
			(layer "B.Fab")
			(hide yes)
			(effects
				(font
					(size 1.27 0.9652)
					(thickness 0.000001)
				)
				(justify left mirror)
			)
		)
		(duplicate_pad_numbers_are_jumpers no)
		(fp_circle
			(center 0 0)
			(end -0.127 0)
			(stroke
				(width 0.2032)
				(type default)
			)
			(fill no)
			(layer "B.SilkS")
		)
		(fp_poly
			(pts
				(xy -0.7874 -1.6637) (xy 0.7874 -1.6637) (xy 0.7874 1.6637) (xy -0.7874 1.6637)
			)
			(stroke
				(width 0)
				(type default)
			)
			(fill no)
			(layer "B.CrtYd")
		)
		(fp_line
			(start 0.4064 0.8128)
			(end 0.4064 -0.7874)
			(stroke
				(width 0.0254)
				(type default)
			)
			(layer "B.Fab")
		)
		(fp_line
			(start 0.4064 -0.7874)
			(end -0.4064 -0.7874)
			(stroke
				(width 0.0254)
				(type default)
			)
			(layer "B.Fab")
		)
		(fp_line
			(start -0.4064 0.8128)
			(end 0.4064 0.8128)
			(stroke
				(width 0.0254)
				(type default)
			)
			(layer "B.Fab")
		)
		(fp_line
			(start -0.4064 -0.7874)
			(end -0.4064 0.8128)
			(stroke
				(width 0.0254)
				(type default)
			)
			(layer "B.Fab")
		)
		(pad "1" smd rect
			(at 0 -0.8001)
			(size 0.8636 0.9652)
			(layers "B.Cu" "B.Mask" "B.Paste")
			(net "VDD_CORE")
		)
		(pad "2" smd rect
			(at 0 0.8001)
			(size 0.8636 0.9652)
			(layers "B.Cu" "B.Mask" "B.Paste")
			(net "GND")
		)
		(zone
			(layer "B.Cu")
			(hatch none 0.5)
			(connect_pads
				(clearance 0)
			)
			(min_thickness 0.25)
			(keepout
				(tracks not_allowed)
				(vias allowed)
				(pads allowed)
				(copperpour not_allowed)
				(footprints allowed)
			)
			(placement
				(enabled no)
				(sheetname "")
			)
			(fill
				(thermal_gap 0.5)
				(thermal_bridge_width 0.5)
				(island_removal_mode 0)
			)
			(polygon
				(pts
					(xy 54.6735 25.1968) (xy 54.8005 25.1968) (xy 54.8005 24.6888) (xy 54.6735 24.6888)
				)
			)
		)
	)
	(footprint ""
		(layer "B.Cu")
		(at 81.850992 18.255996)
		(property "Reference" "V2_A-A12"
			(at 0 0 0)
			(layer "B.SilkS")
			(hide yes)
			(effects
				(font
					(size 1.27 1.27)
				)
				(justify mirror)
			)
		)
		(property "Value" ""
			(at 0 0 0)
			(layer "B.Fab")
			(effects
				(font
					(size 1.27 1.27)
				)
				(justify mirror)
			)
		)
		(duplicate_pad_numbers_are_jumpers no)
		(pad "1" thru_hole circle
			(at 0 0 180)
			(size 0.4572 0.4572)
			(drill 0.20574)
			(layers "*.Cu" "*.Mask")
			(remove_unused_layers no)
			(net "DDR0_32A_A12")
			(clearance 0.1143)
			(thermal_gap 0.1143)
		)
	)
	(footprint ""
		(layer "B.Cu")
		(at 57.236995 31.541974)
		(property "Reference" "C198"
			(at 0 0 0)
			(layer "B.SilkS")
			(hide yes)
			(effects
				(font
					(size 1.27 1.27)
				)
				(justify mirror)
			)
		)
		(property "Value" ""
			(at 0 0 0)
			(layer "B.Fab")
			(effects
				(font
					(size 1.27 1.27)
				)
				(justify mirror)
			)
		)
		(duplicate_pad_numbers_are_jumpers no)
		(fp_circle
			(center 0 0)
			(end 0.104648 0)
			(stroke
				(width 0.1016)
				(type default)
			)
			(fill no)
			(layer "B.SilkS")
		)
		(fp_poly
			(pts
				(xy 0.381 -0.889) (xy 0.381 0.889) (xy -0.381 0.889) (xy -0.381 -0.889)
			)
			(stroke
				(width 0)
				(type default)
			)
			(fill no)
			(layer "B.CrtYd")
		)
		(fp_line
			(start -0.508 -1.016)
			(end -0.508 1.016)
			(stroke
				(width 0.0254)
				(type default)
			)
			(layer "B.Fab")
		)
		(fp_line
			(start -0.508 1.016)
			(end 0.508 1.016)
			(stroke
				(width 0.0254)
				(type default)
			)
			(layer "B.Fab")
		)
		(fp_line
			(start 0.254 -1.016)
			(end -0.508 -1.016)
			(stroke
				(width 0.0254)
				(type default)
			)
			(layer "B.Fab")
		)
		(fp_line
			(start 0.508 -1.016)
			(end 0.254 -1.016)
			(stroke
				(width 0.0254)
				(type default)
			)
			(layer "B.Fab")
		)
		(fp_line
			(start 0.508 1.016)
			(end 0.508 -1.016)
			(stroke
				(width 0.0254)
				(type default)
			)
			(layer "B.Fab")
		)
		(pad "1" smd custom
			(at 0 -0.500126 180)
			(size 0.127 0.127)
			(layers "B.Cu" "B.Mask" "B.Paste")
			(net "VDD_CORE")
			(options
				(clearance outline)
				(anchor circle)
			)
			(primitives
				(gr_poly
					(pts
						(xy -0.1778 0.254) (xy 0.1778 0.254) (xy 0.254 0.1778) (xy 0.254 -0.1778) (xy 0.1778 -0.254) (xy -0.1778 -0.254)
						(xy -0.254 -0.1778) (xy -0.254 0.1778)
					)
					(width 0)
					(fill yes)
				)
			)
		)
		(pad "2" smd custom
			(at 0 0.500126 180)
			(size 0.127 0.127)
			(layers "B.Cu" "B.Mask" "B.Paste")
			(net "GND")
			(options
				(clearance outline)
				(anchor circle)
			)
			(primitives
				(gr_poly
					(pts
						(xy -0.1778 0.254) (xy 0.1778 0.254) (xy 0.254 0.1778) (xy 0.254 -0.1778) (xy 0.1778 -0.254) (xy -0.1778 -0.254)
						(xy -0.254 -0.1778) (xy -0.254 0.1778)
					)
					(width 0)
					(fill yes)
				)
			)
		)
	)
	(footprint ""
		(layer "B.Cu")
		(at 74.651006 6.698996)
		(property "Reference" "V_A-DM0"
			(at 0 0 0)
			(layer "B.SilkS")
			(hide yes)
			(effects
				(font
					(size 1.27 1.27)
				)
				(justify mirror)
			)
		)
		(property "Value" ""
			(at 0 0 0)
			(layer "B.Fab")
			(effects
				(font
					(size 1.27 1.27)
				)
				(justify mirror)
			)
		)
		(duplicate_pad_numbers_are_jumpers no)
		(pad "1" thru_hole circle
			(at 0 0 180)
			(size 0.4572 0.4572)
			(drill 0.20574)
			(layers "*.Cu" "*.Mask")
			(remove_unused_layers no)
			(net "DDR0_32A_DM0")
			(clearance 0.1143)
			(thermal_gap 0.1143)
		)
	)
	(footprint ""
		(layer "B.Cu")
		(at 41.237027 7.542022 180)
		(property "Reference" "C274"
			(at 1.512697 1.827022 270)
			(unlocked yes)
			(layer "B.SilkS")
			(effects
				(font
					(size 0.7874 0.5842)
					(thickness 0.127)
				)
				(justify mirror)
			)
		)
		(property "Value" ""
			(at 0 0 0)
			(layer "B.Fab")
			(effects
				(font
					(size 1.27 1.27)
				)
				(justify mirror)
			)
		)
		(duplicate_pad_numbers_are_jumpers no)
		(fp_circle
			(center 0 0)
			(end -0.104648 0)
			(stroke
				(width 0.1016)
				(type default)
			)
			(fill no)
			(layer "B.SilkS")
		)
		(fp_poly
			(pts
				(xy 0.381 -0.889) (xy 0.381 0.889) (xy -0.381 0.889) (xy -0.381 -0.889)
			)
			(stroke
				(width 0)
				(type default)
			)
			(fill no)
			(layer "B.CrtYd")
		)
		(fp_line
			(start 0.508 1.016)
			(end 0.508 -1.016)
			(stroke
				(width 0.0254)
				(type default)
			)
			(layer "B.Fab")
		)
		(fp_line
			(start 0.508 -1.016)
			(end 0.254 -1.016)
			(stroke
				(width 0.0254)
				(type default)
			)
			(layer "B.Fab")
		)
		(fp_line
			(start 0.254 -1.016)
			(end -0.508 -1.016)
			(stroke
				(width 0.0254)
				(type default)
			)
			(layer "B.Fab")
		)
		(fp_line
			(start -0.508 1.016)
			(end 0.508 1.016)
			(stroke
				(width 0.0254)
				(type default)
			)
			(layer "B.Fab")
		)
		(fp_line
			(start -0.508 -1.016)
			(end -0.508 1.016)
			(stroke
				(width 0.0254)
				(type default)
			)
			(layer "B.Fab")
		)
		(pad "1" smd custom
			(at 0 -0.500126)
			(size 0.127 0.127)
			(layers "B.Cu" "B.Mask" "B.Paste")
			(net "VDD_1.2V")
			(options
				(clearance outline)
				(anchor circle)
			)
			(primitives
				(gr_poly
					(pts
						(xy -0.1778 0.254) (xy 0.1778 0.254) (xy 0.254 0.1778) (xy 0.254 -0.1778) (xy 0.1778 -0.254) (xy -0.1778 -0.254)
						(xy -0.254 -0.1778) (xy -0.254 0.1778)
					)
					(width 0)
					(fill yes)
				)
			)
		)
		(pad "2" smd custom
			(at 0 0.500126)
			(size 0.127 0.127)
			(layers "B.Cu" "B.Mask" "B.Paste")
			(net "GND")
			(options
				(clearance outline)
				(anchor circle)
			)
			(primitives
				(gr_poly
					(pts
						(xy -0.1778 0.254) (xy 0.1778 0.254) (xy 0.254 0.1778) (xy 0.254 -0.1778) (xy 0.1778 -0.254) (xy -0.1778 -0.254)
						(xy -0.254 -0.1778) (xy -0.254 0.1778)
					)
					(width 0)
					(fill yes)
				)
			)
		)
	)
	(footprint ""
		(layer "B.Cu")
		(at 39.237031 24.541988)
		(property "Reference" "C74"
			(at 0 0 0)
			(layer "B.SilkS")
			(hide yes)
			(effects
				(font
					(size 1.27 1.27)
				)
				(justify mirror)
			)
		)
		(property "Value" ""
			(at 0 0 0)
			(layer "B.Fab")
			(effects
				(font
					(size 1.27 1.27)
				)
				(justify mirror)
			)
		)
		(duplicate_pad_numbers_are_jumpers no)
		(fp_circle
			(center 0 0)
			(end 0.104648 0)
			(stroke
				(width 0.1016)
				(type default)
			)
			(fill no)
			(layer "B.SilkS")
		)
		(fp_poly
			(pts
				(xy 0.381 -0.889) (xy 0.381 0.889) (xy -0.381 0.889) (xy -0.381 -0.889)
			)
			(stroke
				(width 0)
				(type default)
			)
			(fill no)
			(layer "B.CrtYd")
		)
		(fp_line
			(start -0.508 -1.016)
			(end -0.508 1.016)
			(stroke
				(width 0.0254)
				(type default)
			)
			(layer "B.Fab")
		)
		(fp_line
			(start -0.508 1.016)
			(end 0.508 1.016)
			(stroke
				(width 0.0254)
				(type default)
			)
			(layer "B.Fab")
		)
		(fp_line
			(start 0.254 -1.016)
			(end -0.508 -1.016)
			(stroke
				(width 0.0254)
				(type default)
			)
			(layer "B.Fab")
		)
		(fp_line
			(start 0.508 -1.016)
			(end 0.254 -1.016)
			(stroke
				(width 0.0254)
				(type default)
			)
			(layer "B.Fab")
		)
		(fp_line
			(start 0.508 1.016)
			(end 0.508 -1.016)
			(stroke
				(width 0.0254)
				(type default)
			)
			(layer "B.Fab")
		)
		(pad "1" smd custom
			(at 0 -0.500126 180)
			(size 0.127 0.127)
			(layers "B.Cu" "B.Mask" "B.Paste")
			(net "VDDA_TS0")
			(options
				(clearance outline)
				(anchor circle)
			)
			(primitives
				(gr_poly
					(pts
						(xy -0.1778 0.254) (xy 0.1778 0.254) (xy 0.254 0.1778) (xy 0.254 -0.1778) (xy 0.1778 -0.254) (xy -0.1778 -0.254)
						(xy -0.254 -0.1778) (xy -0.254 0.1778)
					)
					(width 0)
					(fill yes)
				)
			)
		)
		(pad "2" smd custom
			(at 0 0.500126 180)
			(size 0.127 0.127)
			(layers "B.Cu" "B.Mask" "B.Paste")
			(net "GND")
			(options
				(clearance outline)
				(anchor circle)
			)
			(primitives
				(gr_poly
					(pts
						(xy -0.1778 0.254) (xy 0.1778 0.254) (xy 0.254 0.1778) (xy 0.254 -0.1778) (xy 0.1778 -0.254) (xy -0.1778 -0.254)
						(xy -0.254 -0.1778) (xy -0.254 0.1778)
					)
					(width 0)
					(fill yes)
				)
			)
		)
	)
	(footprint ""
		(layer "B.Cu")
		(at 83.450989 6.698996)
		(property "Reference" "V1_A-A11"
			(at 0 0 0)
			(layer "B.SilkS")
			(hide yes)
			(effects
				(font
					(size 1.27 1.27)
				)
				(justify mirror)
			)
		)
		(property "Value" ""
			(at 0 0 0)
			(layer "B.Fab")
			(effects
				(font
					(size 1.27 1.27)
				)
				(justify mirror)
			)
		)
		(duplicate_pad_numbers_are_jumpers no)
		(pad "1" thru_hole circle
			(at 0 0 180)
			(size 0.4572 0.4572)
			(drill 0.20574)
			(layers "*.Cu" "*.Mask")
			(remove_unused_layers no)
			(net "DDR0_32A_A11")
			(clearance 0.1143)
			(thermal_gap 0.1143)
		)
	)
	(footprint ""
		(layer "B.Cu")
		(at 73.851008 5.898998)
		(property "Reference" "V_A-DQS1-P"
			(at 0 0 0)
			(layer "B.SilkS")
			(hide yes)
			(effects
				(font
					(size 1.27 1.27)
				)
				(justify mirror)
			)
		)
		(property "Value" ""
			(at 0 0 0)
			(layer "B.Fab")
			(effects
				(font
					(size 1.27 1.27)
				)
				(justify mirror)
			)
		)
		(duplicate_pad_numbers_are_jumpers no)
		(pad "1" thru_hole circle
			(at 0 0 180)
			(size 0.4572 0.4572)
			(drill 0.20574)
			(layers "*.Cu" "*.Mask")
			(remove_unused_layers no)
			(net "DDR0_32A_DQS1_P")
			(clearance 0.1143)
			(thermal_gap 0.1143)
		)
	)
)
